(kicad_pcb
	(version 20260206)
	(generator "pcbnew")
	(generator_version "10.0")
	(general
		(thickness 1.6)
		(legacy_teardrops no)
	)
	(paper "A4")
	(title_block
		(title "04192023_DAF0TMB3IC0_F0TG_MB_C_brd_V02_OCP.brd")
		(comment 1 "Grand Teton / footprints 1596-1600 of 8354")
	)
	(layers
		(0 "F.Cu" signal "TOP")
		(4 "In1.Cu" signal "GND")
		(6 "In2.Cu" signal "IN1")
		(8 "In3.Cu" signal "GND1")
		(10 "In4.Cu" signal "IN2")
		(12 "In5.Cu" signal "GND2")
		(14 "In6.Cu" signal "IN3")
		(16 "In7.Cu" signal "GND3")
		(18 "In8.Cu" signal "VCC")
		(20 "In9.Cu" signal "VCC1")
		(22 "In10.Cu" signal "GND4")
		(24 "In11.Cu" signal "IN4")
		(26 "In12.Cu" signal "GND5")
		(28 "In13.Cu" signal "IN5")
		(30 "In14.Cu" signal "GND6")
		(32 "In15.Cu" signal "IN6")
		(34 "In16.Cu" signal "GND7")
		(2 "B.Cu" signal "BOTTOM")
		(9 "F.Adhes" user "F.Adhesive")
		(11 "B.Adhes" user "B.Adhesive")
		(13 "F.Paste" user "Package Geometry/Pastemask Top")
		(15 "B.Paste" user "Package Geometry/Pastemask Bottom")
		(5 "F.SilkS" user "Ref Des/Silkscreen Top")
		(7 "B.SilkS" user "Ref Des/Silkscreen Bottom")
		(1 "F.Mask" user "Board Geometry/Soldermask Top")
		(3 "B.Mask" user "Board Geometry/Soldermask Bottom")
		(17 "Dwgs.User" user "User.Drawings")
		(19 "Cmts.User" user "User.Comments")
		(21 "Eco1.User" user "User.Eco1")
		(23 "Eco2.User" user "User.Eco2")
		(25 "Edge.Cuts" user "Board Geometry/Outline")
		(27 "Margin" user)
		(31 "F.CrtYd" user "Package Geometry/Place Bound Top")
		(29 "B.CrtYd" user "Package Geometry/Place Bound Bottom")
		(35 "F.Fab" user "Ref Des/Assembly Top")
		(33 "B.Fab" user "Ref Des/Assembly Bottom")
	)
	(footprint ""
		(layer "F.Cu")
		(at 226.915472 -290.341812 90)
		(property "Reference" "PR6524"
			(at 0 0 90)
			(layer "F.SilkS")
			(hide yes)
			(effects
				(font
					(size 1.27 1.27)
				)
			)
		)
		(property "Value" ""
			(at 0 0 90)
			(layer "F.Fab")
			(effects
				(font
					(size 1.27 1.27)
				)
			)
		)
		(duplicate_pad_numbers_are_jumpers no)
		(fp_line
			(start 0.7874 -0.4064)
			(end 0.7874 0.4064)
			(stroke
				(width 0.1524)
				(type default)
			)
			(layer "F.SilkS")
		)
		(fp_line
			(start -0.7874 -0.4064)
			(end 0.7874 -0.4064)
			(stroke
				(width 0.1524)
				(type default)
			)
			(layer "F.SilkS")
		)
		(fp_line
			(start 0.7874 0.4064)
			(end -0.7874 0.4064)
			(stroke
				(width 0.1524)
				(type default)
			)
			(layer "F.SilkS")
		)
		(fp_line
			(start -0.7874 0.4064)
			(end -0.7874 -0.4064)
			(stroke
				(width 0.1524)
				(type default)
			)
			(layer "F.SilkS")
		)
		(fp_line
			(start -0.12065 -0.305054)
			(end -0.12065 -0.2794)
			(stroke
				(width 0.1)
				(type default)
			)
			(layer "F.Fab")
		)
		(fp_line
			(start -0.67945 -0.305054)
			(end -0.12065 -0.305054)
			(stroke
				(width 0.1)
				(type default)
			)
			(layer "F.Fab")
		)
		(fp_line
			(start 0.67945 -0.3048)
			(end 0.67945 0.3048)
			(stroke
				(width 0.1)
				(type default)
			)
			(layer "F.Fab")
		)
		(fp_line
			(start 0.12065 -0.3048)
			(end 0.67945 -0.3048)
			(stroke
				(width 0.1)
				(type default)
			)
			(layer "F.Fab")
		)
		(fp_line
			(start 0.12065 -0.2794)
			(end 0.12065 -0.3048)
			(stroke
				(width 0.1)
				(type default)
			)
			(layer "F.Fab")
		)
		(fp_line
			(start -0.12065 -0.2794)
			(end 0.12065 -0.2794)
			(stroke
				(width 0.1)
				(type default)
			)
			(layer "F.Fab")
		)
		(fp_line
			(start 0.120396 0.2794)
			(end -0.12065 0.2794)
			(stroke
				(width 0.1)
				(type default)
			)
			(layer "F.Fab")
		)
		(fp_line
			(start -0.12065 0.2794)
			(end -0.12065 0.3048)
			(stroke
				(width 0.1)
				(type default)
			)
			(layer "F.Fab")
		)
		(fp_line
			(start 0.67945 0.3048)
			(end 0.120396 0.3048)
			(stroke
				(width 0.1)
				(type default)
			)
			(layer "F.Fab")
		)
		(fp_line
			(start 0.120396 0.3048)
			(end 0.120396 0.2794)
			(stroke
				(width 0.1)
				(type default)
			)
			(layer "F.Fab")
		)
		(fp_line
			(start -0.12065 0.3048)
			(end -0.67945 0.3048)
			(stroke
				(width 0.1)
				(type default)
			)
			(layer "F.Fab")
		)
		(fp_line
			(start -0.67945 0.3048)
			(end -0.67945 -0.305054)
			(stroke
				(width 0.1)
				(type default)
			)
			(layer "F.Fab")
		)
		(pad "1" smd circle
			(at -0.40005 0 90)
			(size 0 0)
			(layers "F.Cu" "F.Mask" "F.Paste")
			(net "P1V8_RETIMER_CPU1_FB")
		)
		(pad "2" smd circle
			(at 0.40005 0 90)
			(size 0 0)
			(layers "F.Cu" "F.Mask" "F.Paste")
			(net "P1V8_CPU1_RT_1D")
		)
	)
	(footprint ""
		(layer "F.Cu")
		(at 448.939666 -401.93087)
		(property "Reference" "PC6555_1"
			(at 0 0 0)
			(layer "F.SilkS")
			(hide yes)
			(effects
				(font
					(size 1.27 1.27)
				)
			)
		)
		(property "Value" ""
			(at 0 0 0)
			(layer "F.Fab")
			(effects
				(font
					(size 1.27 1.27)
				)
			)
		)
		(duplicate_pad_numbers_are_jumpers no)
		(fp_line
			(start -0.7874 -0.4064)
			(end 0.7874 -0.4064)
			(stroke
				(width 0.1524)
				(type default)
			)
			(layer "F.SilkS")
		)
		(fp_line
			(start -0.7874 0.4064)
			(end -0.7874 -0.4064)
			(stroke
				(width 0.1524)
				(type default)
			)
			(layer "F.SilkS")
		)
		(fp_line
			(start 0.7874 -0.4064)
			(end 0.7874 0.4064)
			(stroke
				(width 0.1524)
				(type default)
			)
			(layer "F.SilkS")
		)
		(fp_line
			(start 0.7874 0.4064)
			(end -0.7874 0.4064)
			(stroke
				(width 0.1524)
				(type default)
			)
			(layer "F.SilkS")
		)
		(fp_line
			(start -0.67945 -0.305054)
			(end -0.12065 -0.305054)
			(stroke
				(width 0.1)
				(type default)
			)
			(layer "F.Fab")
		)
		(fp_line
			(start -0.67945 0.3048)
			(end -0.67945 -0.305054)
			(stroke
				(width 0.1)
				(type default)
			)
			(layer "F.Fab")
		)
		(fp_line
			(start -0.12065 -0.305054)
			(end -0.12065 -0.2794)
			(stroke
				(width 0.1)
				(type default)
			)
			(layer "F.Fab")
		)
		(fp_line
			(start -0.12065 -0.2794)
			(end 0.12065 -0.2794)
			(stroke
				(width 0.1)
				(type default)
			)
			(layer "F.Fab")
		)
		(fp_line
			(start -0.12065 0.2794)
			(end -0.12065 0.3048)
			(stroke
				(width 0.1)
				(type default)
			)
			(layer "F.Fab")
		)
		(fp_line
			(start -0.12065 0.3048)
			(end -0.67945 0.3048)
			(stroke
				(width 0.1)
				(type default)
			)
			(layer "F.Fab")
		)
		(fp_line
			(start 0.120396 0.2794)
			(end -0.12065 0.2794)
			(stroke
				(width 0.1)
				(type default)
			)
			(layer "F.Fab")
		)
		(fp_line
			(start 0.120396 0.3048)
			(end 0.120396 0.2794)
			(stroke
				(width 0.1)
				(type default)
			)
			(layer "F.Fab")
		)
		(fp_line
			(start 0.12065 -0.3048)
			(end 0.67945 -0.3048)
			(stroke
				(width 0.1)
				(type default)
			)
			(layer "F.Fab")
		)
		(fp_line
			(start 0.12065 -0.2794)
			(end 0.12065 -0.3048)
			(stroke
				(width 0.1)
				(type default)
			)
			(layer "F.Fab")
		)
		(fp_line
			(start 0.67945 -0.3048)
			(end 0.67945 0.3048)
			(stroke
				(width 0.1)
				(type default)
			)
			(layer "F.Fab")
		)
		(fp_line
			(start 0.67945 0.3048)
			(end 0.120396 0.3048)
			(stroke
				(width 0.1)
				(type default)
			)
			(layer "F.Fab")
		)
		(pad "1" smd circle
			(at -0.40005 0)
			(size 0 0)
			(layers "F.Cu" "F.Mask" "F.Paste")
			(net "SW_P12V_AUX_P0V9_RETIMER_CPU0_FLT")
		)
		(pad "2" smd circle
			(at 0.40005 0)
			(size 0 0)
			(layers "F.Cu" "F.Mask" "F.Paste")
			(net "GND")
		)
	)
	(footprint ""
		(layer "F.Cu")
		(at 350.631506 -416.899344 -90)
		(property "Reference" "C6531"
			(at 0 0 270)
			(layer "F.SilkS")
			(hide yes)
			(effects
				(font
					(size 1.27 1.27)
				)
			)
		)
		(property "Value" ""
			(at 0 0 270)
			(layer "F.Fab")
			(effects
				(font
					(size 1.27 1.27)
				)
			)
		)
		(duplicate_pad_numbers_are_jumpers no)
		(fp_line
			(start -0.299974 0.150114)
			(end -0.299974 -0.150114)
			(stroke
				(width 0.1)
				(type default)
			)
			(layer "F.Fab")
		)
		(fp_line
			(start 0.299974 0.150114)
			(end -0.299974 0.150114)
			(stroke
				(width 0.1)
				(type default)
			)
			(layer "F.Fab")
		)
		(fp_line
			(start -0.299974 -0.150114)
			(end 0.299974 -0.150114)
			(stroke
				(width 0.1)
				(type default)
			)
			(layer "F.Fab")
		)
		(fp_line
			(start 0.299974 -0.150114)
			(end 0.299974 0.150114)
			(stroke
				(width 0.1)
				(type default)
			)
			(layer "F.Fab")
		)
		(pad "1" smd rect
			(at -0.2667 0 270)
			(size 0.3048 0.381)
			(layers "F.Cu" "F.Mask" "F.Paste")
			(net "P5E_CPU0_P0_TX_BUF_C_DP<15>")
		)
		(pad "2" smd rect
			(at 0.2667 0 270)
			(size 0.3048 0.381)
			(layers "F.Cu" "F.Mask" "F.Paste")
			(net "P5E_CPU0_P0_TX_BUF_DP<15>")
		)
	)
	(footprint ""
		(layer "F.Cu")
		(at 47.45482 -102.41534 90)
		(property "Reference" "U60"
			(at -1.25476 -1.89357 90)
			(unlocked yes)
			(layer "F.SilkS")
			(effects
				(font
					(size 0.7874 0.5842)
					(thickness 0.1524)
				)
				(justify left)
			)
		)
		(property "Value" ""
			(at 0 0 90)
			(layer "F.Fab")
			(effects
				(font
					(size 1.27 1.27)
				)
			)
		)
		(duplicate_pad_numbers_are_jumpers no)
		(fp_line
			(start 1.335278 -1.100074)
			(end -1.335278 -1.100074)
			(stroke
				(width 0.1524)
				(type default)
			)
			(layer "F.SilkS")
		)
		(fp_line
			(start -1.335278 -1.100074)
			(end -1.335278 1.100074)
			(stroke
				(width 0.1524)
				(type default)
			)
			(layer "F.SilkS")
		)
		(fp_line
			(start 1.335278 1.100074)
			(end 1.335278 -1.100074)
			(stroke
				(width 0.1524)
				(type default)
			)
			(layer "F.SilkS")
		)
		(fp_line
			(start -1.335278 1.100074)
			(end 1.335278 1.100074)
			(stroke
				(width 0.1524)
				(type default)
			)
			(layer "F.SilkS")
		)
		(fp_line
			(start 0.674878 -1.100074)
			(end -0.674878 -1.100074)
			(stroke
				(width 0.1)
				(type default)
			)
			(layer "F.Fab")
		)
		(fp_line
			(start -0.674878 -1.100074)
			(end -0.674878 1.100074)
			(stroke
				(width 0.1)
				(type default)
			)
			(layer "F.Fab")
		)
		(fp_line
			(start 0.674878 1.100074)
			(end 0.674878 -1.100074)
			(stroke
				(width 0.1)
				(type default)
			)
			(layer "F.Fab")
		)
		(fp_line
			(start -0.674878 1.100074)
			(end 0.674878 1.100074)
			(stroke
				(width 0.1)
				(type default)
			)
			(layer "F.Fab")
		)
		(pad "1" smd rect
			(at -0.8001 0.649986)
			(size 0.6096 0.8128)
			(layers "F.Cu" "F.Mask" "F.Paste")
			(net "P3V3_AUX_DSC_VOL")
		)
		(pad "2" smd rect
			(at -0.8001 -0.649986)
			(size 0.6096 0.8128)
			(layers "F.Cu" "F.Mask" "F.Paste")
			(net "Net_10856")
		)
		(pad "3" smd rect
			(at 0.8001 0)
			(size 0.6096 0.8128)
			(layers "F.Cu" "F.Mask" "F.Paste")
			(net "P3V3_AUX_DSC_S1")
		)
	)
	(footprint ""
		(layer "F.Cu")
		(at 25.640792 -388.854188)
		(property "Reference" "PU6512"
			(at 2.525014 -4.833874 0)
			(unlocked yes)
			(layer "F.SilkS")
			(effects
				(font
					(size 0.7874 0.5842)
					(thickness 0.1524)
				)
				(justify left)
			)
		)
		(property "Value" ""
			(at 0 0 0)
			(layer "F.Fab")
			(effects
				(font
					(size 1.27 1.27)
				)
			)
		)
		(duplicate_pad_numbers_are_jumpers no)
		(fp_line
			(start -2.500122 -2.999994)
			(end -2.24409 -2.999994)
			(stroke
				(width 0.1524)
				(type default)
			)
			(layer "F.SilkS")
		)
		(fp_line
			(start -2.500122 -2.529078)
			(end -2.500122 -2.999994)
			(stroke
				(width 0.1524)
				(type default)
			)
			(layer "F.SilkS")
		)
		(fp_line
			(start -2.500122 0.6604)
			(end -2.500122 0.229108)
			(stroke
				(width 0.1524)
				(type default)
			)
			(layer "F.SilkS")
		)
		(fp_line
			(start -2.500122 2.999994)
			(end -2.500122 2.339594)
			(stroke
				(width 0.1524)
				(type default)
			)
			(layer "F.SilkS")
		)
		(fp_line
			(start -2.2987 2.999994)
			(end -2.500122 2.999994)
			(stroke
				(width 0.1524)
				(type default)
			)
			(layer "F.SilkS")
		)
		(fp_line
			(start 2.31394 -2.999994)
			(end 2.500122 -2.999994)
			(stroke
				(width 0.1524)
				(type default)
			)
			(layer "F.SilkS")
		)
		(fp_line
			(start 2.500122 -2.999994)
			(end 2.500122 -2.44348)
			(stroke
				(width 0.1524)
				(type default)
			)
			(layer "F.SilkS")
		)
		(fp_line
			(start 2.500122 2.339594)
			(end 2.500122 2.999994)
			(stroke
				(width 0.1524)
				(type default)
			)
			(layer "F.SilkS")
		)
		(fp_line
			(start 2.500122 2.999994)
			(end 2.2987 2.999994)
			(stroke
				(width 0.1524)
				(type default)
			)
			(layer "F.SilkS")
		)
		(fp_poly
			(pts
				(xy -3.14071 -3.573272) (xy -3.853942 -2.84988) (xy -2.773426 -2.498344)
			)
			(stroke
				(width 0)
				(type default)
			)
			(fill yes)
			(layer "F.SilkS")
		)
		(fp_line
			(start -2.500122 -2.999994)
			(end 2.500122 -2.999994)
			(stroke
				(width 0.1)
				(type default)
			)
			(layer "F.Fab")
		)
		(fp_line
			(start -2.500122 2.999994)
			(end -2.500122 -2.999994)
			(stroke
				(width 0.1)
				(type default)
			)
			(layer "F.Fab")
		)
		(fp_line
			(start 2.500122 -2.999994)
			(end 2.500122 2.999994)
			(stroke
				(width 0.1)
				(type default)
			)
			(layer "F.Fab")
		)
		(fp_line
			(start 2.500122 2.999994)
			(end -2.500122 2.999994)
			(stroke
				(width 0.1)
				(type default)
			)
			(layer "F.Fab")
		)
		(fp_poly
			(pts
				(xy -4.218432 -2.783078) (xy -4.218432 -1.767078) (xy -3.202432 -2.275078)
			)
			(stroke
				(width 0)
				(type default)
			)
			(fill yes)
			(layer "F.Fab")
		)
		(pad "1" smd rect
			(at -2.400046 -2.275078 90)
			(size 0.2286 0.6096)
			(layers "F.Cu" "F.Mask" "F.Paste")
			(net "P0V9_RETIMER_CPU1_VOS2")
		)
		(pad "2" smd rect
			(at -2.400046 -1.82499 90)
			(size 0.2286 0.6096)
			(layers "F.Cu" "F.Mask" "F.Paste")
			(net "GND")
		)
		(pad "3" smd rect
			(at -2.400046 -1.374902 90)
			(size 0.2286 0.6096)
			(layers "F.Cu" "F.Mask" "F.Paste")
			(net "P0V9_RETIMER_CPU1_VCC2")
		)
		(pad "4" smd rect
			(at -2.400046 -0.925068 90)
			(size 0.2286 0.6096)
			(layers "F.Cu" "F.Mask" "F.Paste")
			(net "P0V9_RETIMER_CPU1_PVCC")
		)
		(pad "5" smd rect
			(at -2.400046 -0.47498 90)
			(size 0.2286 0.6096)
			(layers "F.Cu" "F.Mask" "F.Paste")
			(net "GND")
		)
		(pad "6" smd rect
			(at -2.400046 -0.024892 90)
			(size 0.2286 0.6096)
			(layers "F.Cu" "F.Mask" "F.Paste")
			(net "NC_PV09_RETIMER_CPU1_GL1_2")
		)
		(pad "7_9-20_24" smd circle
			(at 0 1.150112 90)
			(size 0 0)
			(layers "F.Cu" "F.Mask" "F.Paste")
			(net "GND")
		)
		(pad "10_19" smd rect
			(at 0 2.899918 90)
			(size 0.6096 4.318)
			(layers "F.Cu" "F.Mask" "F.Paste")
			(net "SW_P0V9_RETIMER_CPU1_SW2")
		)
		(pad "25_29" smd rect
			(at 1.549908 -1.279906 270)
			(size 2.0574 2.3114)
			(layers "F.Cu" "F.Mask" "F.Paste")
			(net "SW_P12V_AUX_P0V9_RETIMER_CPU1_FLT")
		)
		(pad "30" smd rect
			(at 2.05994 -2.899918)
			(size 0.2286 0.6096)
			(layers "F.Cu" "F.Mask" "F.Paste")
			(net "SW_P12V_AUX_P0V9_RETIMER_CPU1_FLT")
		)
		(pad "31" smd rect
			(at 1.610106 -2.899918)
			(size 0.2286 0.6096)
			(layers "F.Cu" "F.Mask" "F.Paste")
			(net "NC_PV09_RETIMER_CPU1_DNC2")
		)
		(pad "32" smd rect
			(at 1.160018 -2.899918)
			(size 0.2286 0.6096)
			(layers "F.Cu" "F.Mask" "F.Paste")
			(net "SW_P0V9_RETIMER_CPU1_PH2")
		)
		(pad "33" smd rect
			(at 0.70993 -2.899918)
			(size 0.2286 0.6096)
			(layers "F.Cu" "F.Mask" "F.Paste")
			(net "SW_P0V9_RETIMER_CPU1_BOOT2")
		)
		(pad "34" smd rect
			(at 0.260096 -2.899918)
			(size 0.2286 0.6096)
			(layers "F.Cu" "F.Mask" "F.Paste")
			(net "P0V9_RETIMER_CPU1_PWM2")
		)
		(pad "35" smd rect
			(at -0.189992 -2.899918)
			(size 0.2286 0.6096)
			(layers "F.Cu" "F.Mask" "F.Paste")
			(net "P0V9_RETIMER_CPU1_VCC2")
		)
		(pad "36" smd rect
			(at -0.64008 -2.899918)
			(size 0.2286 0.6096)
			(layers "F.Cu" "F.Mask" "F.Paste")
			(net "P0V9_RETIMER_CPU1_TEMP0")
		)
		(pad "37" smd rect
			(at -1.089914 -2.899918)
			(size 0.2286 0.6096)
			(layers "F.Cu" "F.Mask" "F.Paste")
			(net "P0V9_RETIMER_CPU1_LSET2")
		)
		(pad "38" smd rect
			(at -1.540002 -2.899918)
			(size 0.2286 0.6096)
			(layers "F.Cu" "F.Mask" "F.Paste")
			(net "P0V9_RETIMER_CPU1_IMON2")
		)
		(pad "39" smd rect
			(at -1.99009 -2.899918)
			(size 0.2286 0.6096)
			(layers "F.Cu" "F.Mask" "F.Paste")
			(net "PV09_RETIMER_CPU1_VCCS")
		)
		(pad "40" smd rect
			(at -0.87503 -1.27508)
			(size 1.7526 1.9558)
			(layers "F.Cu" "F.Mask" "F.Paste")
			(net "GND")
		)
		(pad "41" smd rect
			(at -1.525016 0.249936 270)
			(size 0.3048 0.4572)
			(layers "F.Cu" "F.Mask" "F.Paste")
			(net "NC_PV09_RETIMER_CPU1_GL2_2")
		)
		(zone
			(layer "F.Cu")
			(hatch none 0.5)
			(connect_pads
				(clearance 0)
			)
			(min_thickness 0.25)
			(keepout
				(tracks not_allowed)
				(vias allowed)
				(pads allowed)
				(copperpour not_allowed)
				(footprints allowed)
			)
			(placement
				(enabled no)
				(sheetname "")
			)
			(fill
				(thermal_gap 0.5)
				(thermal_bridge_width 0.5)
				(island_removal_mode 0)
			)
			(polygon
				(pts
					(xy 23.14067 -385.854194) (xy 23.14067 -386.603494) (xy 28.140914 -386.603494) (xy 28.140914 -385.854194)
					(xy 27.850592 -385.854194) (xy 27.850592 -386.30987) (xy 23.430992 -386.30987) (xy 23.430992 -385.854194)
				)
			)
		)
		(zone
			(layer "F.Cu")
			(hatch none 0.5)
			(connect_pads
				(clearance 0)
			)
			(min_thickness 0.25)
			(keepout
				(tracks not_allowed)
				(vias allowed)
				(pads allowed)
				(copperpour not_allowed)
				(footprints allowed)
			)
			(placement
				(enabled no)
				(sheetname "")
			)
			(fill
				(thermal_gap 0.5)
				(thermal_bridge_width 0.5)
				(island_removal_mode 0)
			)
			(polygon
				(pts
					(xy 23.14067 -388.104888) (xy 23.14067 -388.56158) (xy 23.836376 -388.56158) (xy 23.836376 -388.401052)
					(xy 24.395176 -388.401052) (xy 24.395176 -388.807452) (xy 23.836376 -388.807452) (xy 23.836376 -388.58698)
					(xy 23.14067 -388.58698) (xy 23.14067 -388.71398) (xy 23.596346 -388.71398) (xy 23.596346 -390.891522)
					(xy 23.838662 -390.891522) (xy 23.838662 -389.100568) (xy 25.692862 -389.100568) (xy 25.692862 -391.157968)
					(xy 23.838662 -391.157968) (xy 23.838662 -390.916922) (xy 23.596346 -390.916922) (xy 23.596346 -391.398506)
					(xy 28.140914 -391.398506) (xy 28.140914 -391.213594) (xy 25.9842 -391.213594) (xy 25.9842 -389.054594)
					(xy 28.140914 -389.054594) (xy 28.140914 -388.804912) (xy 24.69007 -388.804912) (xy 24.69007 -388.104888)
				)
			)
		)
	)
)
